FILE_TYPE=LIBRARY_PARTS;
primitive 'CRYSTAL','CRYSTAL_SM','CRYSTAL_SMLF';
  pin
    'A':
      PIN_NUMBER='(1)';
      PINUSE='UNSPEC';
      NO_LOAD_CHECK='BOTH';
      NO_IO_CHECK='BOTH';
      ALLOW_CONNECT='TRUE';
      PIN_GROUP='1';
    'B':
      PIN_NUMBER='(2)';
      PINUSE='UNSPEC';
      NO_LOAD_CHECK='BOTH';
      NO_IO_CHECK='BOTH';
      ALLOW_CONNECT='TRUE';
      PIN_GROUP='1';
  end_pin;
  body
    PART_NAME='CRYSTAL';
    PHYS_DES_PREFIX='Y';
  end_body;
end_primitive;

primitive 'CRYSTAL_3215','CRYSTAL_3215LF';
  pin
    'A':
      PIN_NUMBER='(1)';
      PINUSE='UNSPEC';
      NO_LOAD_CHECK='BOTH';
      NO_IO_CHECK='BOTH';
      ALLOW_CONNECT='TRUE';
      PIN_GROUP='1';
    'B':
      PIN_NUMBER='(4)';
      PINUSE='UNSPEC';
      NO_LOAD_CHECK='BOTH';
      NO_IO_CHECK='BOTH';
      ALLOW_CONNECT='TRUE';
      PIN_GROUP='1';
  end_pin;
  body
    NC_PINS='(2,3)';
    PART_NAME='CRYSTAL';
    PHYS_DES_PREFIX='Y';
  end_body;
end_primitive;

primitive 'CRYSTAL_5020';
  pin
    'A':
      PIN_NUMBER='(1)';
      PINUSE='UNSPEC';
      NO_LOAD_CHECK='BOTH';
      NO_IO_CHECK='BOTH';
      ALLOW_CONNECT='TRUE';
      PIN_GROUP='1';
    'B':
      PIN_NUMBER='(2)';
      PINUSE='UNSPEC';
      NO_LOAD_CHECK='BOTH';
      NO_IO_CHECK='BOTH';
      ALLOW_CONNECT='TRUE';
      PIN_GROUP='1';
  end_pin;
  body
    PART_NAME='CRYSTAL';
    PHYS_DES_PREFIX='Y';
    NC_PINS='(3,4)';  
    end_body;
end_primitive;

primitive 'CRYSTAL_5030LF';
  pin
    'A':
      PIN_NUMBER='(1)';
      PINUSE='UNSPEC';
      NO_LOAD_CHECK='BOTH';
      NO_IO_CHECK='BOTH';
      ALLOW_CONNECT='TRUE';
      PIN_GROUP='1';
    'B':
      PIN_NUMBER='(3)';
      PINUSE='UNSPEC';
      NO_LOAD_CHECK='BOTH';
      NO_IO_CHECK='BOTH';
      ALLOW_CONNECT='TRUE';
      PIN_GROUP='1';
  end_pin;
  body
    PART_NAME='CRYSTAL';
    PHYS_DES_PREFIX='Y';
    NC_PINS='(2,4)';  
    end_body;
end_primitive;

primitive 'CRYSTAL_2013LF','CRYSTAL_2013';
  pin
    'A':
      PIN_NUMBER='(1)';
      PINUSE='UNSPEC';
      NO_LOAD_CHECK='BOTH';
      NO_IO_CHECK='BOTH';
      ALLOW_CONNECT='TRUE';
      PIN_GROUP='1';
    'B':
      PIN_NUMBER='(3)';
      PINUSE='UNSPEC';
      NO_LOAD_CHECK='BOTH';
      NO_IO_CHECK='BOTH';
      ALLOW_CONNECT='TRUE';
      PIN_GROUP='1';
  end_pin;
  body
    POWER_PINS='(GND:2,4)';
    PART_NAME='CRYSTAL';
    PHYS_DES_PREFIX='Y';
    end_body;
end_primitive;

primitive 'CRYSTAL_SMD';
  pin
    'A':
      PIN_NUMBER='(1)';
      PINUSE='UNSPEC';
      NO_LOAD_CHECK='BOTH';
      NO_IO_CHECK='BOTH';
      ALLOW_CONNECT='TRUE';
      PIN_GROUP='1';
    'B':
      PIN_NUMBER='(2)';
      PINUSE='UNSPEC';
      NO_LOAD_CHECK='BOTH';
      NO_IO_CHECK='BOTH';
      ALLOW_CONNECT='TRUE';
      PIN_GROUP='1';
  end_pin;
  body
    POWER_PINS='(GND:3)';
    PART_NAME='CRYSTAL';
    PHYS_DES_PREFIX='Y';
  end_body;
end_primitive;

END.
